(kicad_pcb
	(version 20260206)
	(generator "pcbnew")
	(generator_version "10.0")
	(general
		(thickness 1.6)
		(legacy_teardrops no)
	)
	(paper "A4")
	(title_block
		(title "01162023_DA0F0TEBIF0_F0T_Expander_BD_F_brd_V02_OCP.brd")
		(comment 1 "Grand Teton / footprints 2427-2433 of 9728")
	)
	(layers
		(0 "F.Cu" signal "TOP")
		(4 "In1.Cu" signal "GND")
		(6 "In2.Cu" signal "VCC")
		(8 "In3.Cu" signal "VCC1")
		(10 "In4.Cu" signal "GND1")
		(12 "In5.Cu" signal "IN1")
		(14 "In6.Cu" signal "GND2")
		(16 "In7.Cu" signal "IN2")
		(18 "In8.Cu" signal "GND3")
		(20 "In9.Cu" signal "IN3")
		(22 "In10.Cu" signal "GND4")
		(24 "In11.Cu" signal "IN4")
		(26 "In12.Cu" signal "GND5")
		(28 "In13.Cu" signal "IN5")
		(30 "In14.Cu" signal "GND6")
		(32 "In15.Cu" signal "IN6")
		(34 "In16.Cu" signal "GND7")
		(2 "B.Cu" signal "BOTTOM")
		(9 "F.Adhes" user "F.Adhesive")
		(11 "B.Adhes" user "B.Adhesive")
		(13 "F.Paste" user "Package Geometry/Pastemask Top")
		(15 "B.Paste" user "Package Geometry/Pastemask Bottom")
		(5 "F.SilkS" user "Ref Des/Silkscreen Top")
		(7 "B.SilkS" user "Ref Des/Silkscreen Bottom")
		(1 "F.Mask" user "Board Geometry/Soldermask Top")
		(3 "B.Mask" user "Board Geometry/Soldermask Bottom")
		(17 "Dwgs.User" user "User.Drawings")
		(19 "Cmts.User" user "User.Comments")
		(21 "Eco1.User" user "User.Eco1")
		(23 "Eco2.User" user "User.Eco2")
		(25 "Edge.Cuts" user "Board Geometry/Outline")
		(27 "Margin" user)
		(31 "F.CrtYd" user "Package Geometry/Place Bound Top")
		(29 "B.CrtYd" user "Package Geometry/Place Bound Bottom")
		(35 "F.Fab" user "Ref Des/Assembly Top")
		(33 "B.Fab" user "Ref Des/Assembly Bottom")
	)
	(footprint ""
		(layer "F.Cu")
		(at 218.080844 -96.139 -90)
		(property "Reference" "R715"
			(at 0 0 270)
			(layer "F.SilkS")
			(hide yes)
			(effects
				(font
					(size 1.27 1.27)
				)
			)
		)
		(property "Value" ""
			(at 0 0 270)
			(layer "F.Fab")
			(effects
				(font
					(size 1.27 1.27)
				)
			)
		)
		(duplicate_pad_numbers_are_jumpers no)
		(fp_line
			(start -0.7874 0.4064)
			(end -0.7874 -0.4064)
			(stroke
				(width 0.1524)
				(type default)
			)
			(layer "F.SilkS")
		)
		(fp_line
			(start 0.7874 0.4064)
			(end -0.7874 0.4064)
			(stroke
				(width 0.1524)
				(type default)
			)
			(layer "F.SilkS")
		)
		(fp_line
			(start -0.7874 -0.4064)
			(end 0.7874 -0.4064)
			(stroke
				(width 0.1524)
				(type default)
			)
			(layer "F.SilkS")
		)
		(fp_line
			(start 0.7874 -0.4064)
			(end 0.7874 0.4064)
			(stroke
				(width 0.1524)
				(type default)
			)
			(layer "F.SilkS")
		)
		(fp_line
			(start -0.67945 0.3048)
			(end -0.67945 -0.305054)
			(stroke
				(width 0.1)
				(type default)
			)
			(layer "F.Fab")
		)
		(fp_line
			(start -0.12065 0.3048)
			(end -0.67945 0.3048)
			(stroke
				(width 0.1)
				(type default)
			)
			(layer "F.Fab")
		)
		(fp_line
			(start 0.120396 0.3048)
			(end 0.120396 0.2794)
			(stroke
				(width 0.1)
				(type default)
			)
			(layer "F.Fab")
		)
		(fp_line
			(start 0.67945 0.3048)
			(end 0.120396 0.3048)
			(stroke
				(width 0.1)
				(type default)
			)
			(layer "F.Fab")
		)
		(fp_line
			(start -0.12065 0.2794)
			(end -0.12065 0.3048)
			(stroke
				(width 0.1)
				(type default)
			)
			(layer "F.Fab")
		)
		(fp_line
			(start 0.120396 0.2794)
			(end -0.12065 0.2794)
			(stroke
				(width 0.1)
				(type default)
			)
			(layer "F.Fab")
		)
		(fp_line
			(start -0.12065 -0.2794)
			(end 0.12065 -0.2794)
			(stroke
				(width 0.1)
				(type default)
			)
			(layer "F.Fab")
		)
		(fp_line
			(start 0.12065 -0.2794)
			(end 0.12065 -0.3048)
			(stroke
				(width 0.1)
				(type default)
			)
			(layer "F.Fab")
		)
		(fp_line
			(start 0.12065 -0.3048)
			(end 0.67945 -0.3048)
			(stroke
				(width 0.1)
				(type default)
			)
			(layer "F.Fab")
		)
		(fp_line
			(start 0.67945 -0.3048)
			(end 0.67945 0.3048)
			(stroke
				(width 0.1)
				(type default)
			)
			(layer "F.Fab")
		)
		(fp_line
			(start -0.67945 -0.305054)
			(end -0.12065 -0.305054)
			(stroke
				(width 0.1)
				(type default)
			)
			(layer "F.Fab")
		)
		(fp_line
			(start -0.12065 -0.305054)
			(end -0.12065 -0.2794)
			(stroke
				(width 0.1)
				(type default)
			)
			(layer "F.Fab")
		)
		(pad "1" smd circle
			(at -0.40005 0 270)
			(size 0 0)
			(layers "F.Cu" "F.Mask" "F.Paste")
			(net "NIC3_ADC_A0")
		)
		(pad "2" smd circle
			(at 0.40005 0 270)
			(size 0 0)
			(layers "F.Cu" "F.Mask" "F.Paste")
			(net "P3V3_AUX")
		)
	)
	(footprint ""
		(layer "F.Cu")
		(at 129.690114 -261.814564 180)
		(property "Reference" "R830"
			(at 0 0 180)
			(layer "F.SilkS")
			(hide yes)
			(effects
				(font
					(size 1.27 1.27)
				)
			)
		)
		(property "Value" ""
			(at 0 0 180)
			(layer "F.Fab")
			(effects
				(font
					(size 1.27 1.27)
				)
			)
		)
		(duplicate_pad_numbers_are_jumpers no)
		(fp_line
			(start 0.7874 0.4064)
			(end -0.7874 0.4064)
			(stroke
				(width 0.1524)
				(type default)
			)
			(layer "F.SilkS")
		)
		(fp_line
			(start 0.7874 -0.4064)
			(end 0.7874 0.4064)
			(stroke
				(width 0.1524)
				(type default)
			)
			(layer "F.SilkS")
		)
		(fp_line
			(start -0.7874 0.4064)
			(end -0.7874 -0.4064)
			(stroke
				(width 0.1524)
				(type default)
			)
			(layer "F.SilkS")
		)
		(fp_line
			(start -0.7874 -0.4064)
			(end 0.7874 -0.4064)
			(stroke
				(width 0.1524)
				(type default)
			)
			(layer "F.SilkS")
		)
		(fp_line
			(start 0.67945 0.3048)
			(end 0.120396 0.3048)
			(stroke
				(width 0.1)
				(type default)
			)
			(layer "F.Fab")
		)
		(fp_line
			(start 0.67945 -0.3048)
			(end 0.67945 0.3048)
			(stroke
				(width 0.1)
				(type default)
			)
			(layer "F.Fab")
		)
		(fp_line
			(start 0.12065 -0.2794)
			(end 0.12065 -0.3048)
			(stroke
				(width 0.1)
				(type default)
			)
			(layer "F.Fab")
		)
		(fp_line
			(start 0.12065 -0.3048)
			(end 0.67945 -0.3048)
			(stroke
				(width 0.1)
				(type default)
			)
			(layer "F.Fab")
		)
		(fp_line
			(start 0.120396 0.3048)
			(end 0.120396 0.2794)
			(stroke
				(width 0.1)
				(type default)
			)
			(layer "F.Fab")
		)
		(fp_line
			(start 0.120396 0.2794)
			(end -0.12065 0.2794)
			(stroke
				(width 0.1)
				(type default)
			)
			(layer "F.Fab")
		)
		(fp_line
			(start -0.12065 0.3048)
			(end -0.67945 0.3048)
			(stroke
				(width 0.1)
				(type default)
			)
			(layer "F.Fab")
		)
		(fp_line
			(start -0.12065 0.2794)
			(end -0.12065 0.3048)
			(stroke
				(width 0.1)
				(type default)
			)
			(layer "F.Fab")
		)
		(fp_line
			(start -0.12065 -0.2794)
			(end 0.12065 -0.2794)
			(stroke
				(width 0.1)
				(type default)
			)
			(layer "F.Fab")
		)
		(fp_line
			(start -0.12065 -0.305054)
			(end -0.12065 -0.2794)
			(stroke
				(width 0.1)
				(type default)
			)
			(layer "F.Fab")
		)
		(fp_line
			(start -0.67945 0.3048)
			(end -0.67945 -0.305054)
			(stroke
				(width 0.1)
				(type default)
			)
			(layer "F.Fab")
		)
		(fp_line
			(start -0.67945 -0.305054)
			(end -0.12065 -0.305054)
			(stroke
				(width 0.1)
				(type default)
			)
			(layer "F.Fab")
		)
		(pad "1" smd circle
			(at -0.40005 0 180)
			(size 0 0)
			(layers "F.Cu" "F.Mask" "F.Paste")
			(net "PWR_EN_PEX_R")
		)
		(pad "2" smd circle
			(at 0.40005 0 180)
			(size 0 0)
			(layers "F.Cu" "F.Mask" "F.Paste")
			(net "FM_P0V8_PEX1_EN_R")
		)
	)
	(footprint ""
		(layer "F.Cu")
		(at 394.734542 -34.546286 180)
		(property "Reference" "C706"
			(at 0 0 180)
			(layer "F.SilkS")
			(hide yes)
			(effects
				(font
					(size 1.27 1.27)
				)
			)
		)
		(property "Value" ""
			(at 0 0 180)
			(layer "F.Fab")
			(effects
				(font
					(size 1.27 1.27)
				)
			)
		)
		(duplicate_pad_numbers_are_jumpers no)
		(fp_line
			(start 0.299974 0.150114)
			(end -0.299974 0.150114)
			(stroke
				(width 0.1)
				(type default)
			)
			(layer "F.Fab")
		)
		(fp_line
			(start 0.299974 -0.150114)
			(end 0.299974 0.150114)
			(stroke
				(width 0.1)
				(type default)
			)
			(layer "F.Fab")
		)
		(fp_line
			(start -0.299974 0.150114)
			(end -0.299974 -0.150114)
			(stroke
				(width 0.1)
				(type default)
			)
			(layer "F.Fab")
		)
		(fp_line
			(start -0.299974 -0.150114)
			(end 0.299974 -0.150114)
			(stroke
				(width 0.1)
				(type default)
			)
			(layer "F.Fab")
		)
		(pad "1" smd rect
			(at -0.2667 0 180)
			(size 0.3048 0.381)
			(layers "F.Cu" "F.Mask" "F.Paste")
			(net "P5E_PEX3_STN2_TX_DP<43>")
		)
		(pad "2" smd rect
			(at 0.2667 0 180)
			(size 0.3048 0.381)
			(layers "F.Cu" "F.Mask" "F.Paste")
			(net "P5E_PEX3_STN2_TX_C_DP<43>")
		)
	)
	(footprint ""
		(layer "F.Cu")
		(at 121.96699 -52.543456 180)
		(property "Reference" "PC502"
			(at 0 0 180)
			(layer "F.SilkS")
			(hide yes)
			(effects
				(font
					(size 1.27 1.27)
				)
			)
		)
		(property "Value" ""
			(at 0 0 180)
			(layer "F.Fab")
			(effects
				(font
					(size 1.27 1.27)
				)
			)
		)
		(duplicate_pad_numbers_are_jumpers no)
		(fp_line
			(start 0.7874 0.4064)
			(end -0.7874 0.4064)
			(stroke
				(width 0.1524)
				(type default)
			)
			(layer "F.SilkS")
		)
		(fp_line
			(start 0.7874 -0.4064)
			(end 0.7874 0.4064)
			(stroke
				(width 0.1524)
				(type default)
			)
			(layer "F.SilkS")
		)
		(fp_line
			(start -0.7874 0.4064)
			(end -0.7874 -0.4064)
			(stroke
				(width 0.1524)
				(type default)
			)
			(layer "F.SilkS")
		)
		(fp_line
			(start -0.7874 -0.4064)
			(end 0.7874 -0.4064)
			(stroke
				(width 0.1524)
				(type default)
			)
			(layer "F.SilkS")
		)
		(fp_line
			(start 0.67945 0.3048)
			(end 0.120396 0.3048)
			(stroke
				(width 0.1)
				(type default)
			)
			(layer "F.Fab")
		)
		(fp_line
			(start 0.67945 -0.3048)
			(end 0.67945 0.3048)
			(stroke
				(width 0.1)
				(type default)
			)
			(layer "F.Fab")
		)
		(fp_line
			(start 0.12065 -0.2794)
			(end 0.12065 -0.3048)
			(stroke
				(width 0.1)
				(type default)
			)
			(layer "F.Fab")
		)
		(fp_line
			(start 0.12065 -0.3048)
			(end 0.67945 -0.3048)
			(stroke
				(width 0.1)
				(type default)
			)
			(layer "F.Fab")
		)
		(fp_line
			(start 0.120396 0.3048)
			(end 0.120396 0.2794)
			(stroke
				(width 0.1)
				(type default)
			)
			(layer "F.Fab")
		)
		(fp_line
			(start 0.120396 0.2794)
			(end -0.12065 0.2794)
			(stroke
				(width 0.1)
				(type default)
			)
			(layer "F.Fab")
		)
		(fp_line
			(start -0.12065 0.3048)
			(end -0.67945 0.3048)
			(stroke
				(width 0.1)
				(type default)
			)
			(layer "F.Fab")
		)
		(fp_line
			(start -0.12065 0.2794)
			(end -0.12065 0.3048)
			(stroke
				(width 0.1)
				(type default)
			)
			(layer "F.Fab")
		)
		(fp_line
			(start -0.12065 -0.2794)
			(end 0.12065 -0.2794)
			(stroke
				(width 0.1)
				(type default)
			)
			(layer "F.Fab")
		)
		(fp_line
			(start -0.12065 -0.305054)
			(end -0.12065 -0.2794)
			(stroke
				(width 0.1)
				(type default)
			)
			(layer "F.Fab")
		)
		(fp_line
			(start -0.67945 0.3048)
			(end -0.67945 -0.305054)
			(stroke
				(width 0.1)
				(type default)
			)
			(layer "F.Fab")
		)
		(fp_line
			(start -0.67945 -0.305054)
			(end -0.12065 -0.305054)
			(stroke
				(width 0.1)
				(type default)
			)
			(layer "F.Fab")
		)
		(pad "1" smd circle
			(at -0.40005 0 180)
			(size 0 0)
			(layers "F.Cu" "F.Mask" "F.Paste")
			(net "P3V3_SSD4")
		)
		(pad "2" smd circle
			(at 0.40005 0 180)
			(size 0 0)
			(layers "F.Cu" "F.Mask" "F.Paste")
			(net "GND")
		)
	)
	(footprint ""
		(layer "F.Cu")
		(at 10.693146 -151.737822 180)
		(property "Reference" "PR6861"
			(at 0 0 180)
			(layer "F.SilkS")
			(hide yes)
			(effects
				(font
					(size 1.27 1.27)
				)
			)
		)
		(property "Value" ""
			(at 0 0 180)
			(layer "F.Fab")
			(effects
				(font
					(size 1.27 1.27)
				)
			)
		)
		(duplicate_pad_numbers_are_jumpers no)
		(fp_line
			(start 0.7874 0.4064)
			(end -0.7874 0.4064)
			(stroke
				(width 0.1524)
				(type default)
			)
			(layer "F.SilkS")
		)
		(fp_line
			(start 0.7874 -0.4064)
			(end 0.7874 0.4064)
			(stroke
				(width 0.1524)
				(type default)
			)
			(layer "F.SilkS")
		)
		(fp_line
			(start -0.7874 0.4064)
			(end -0.7874 -0.4064)
			(stroke
				(width 0.1524)
				(type default)
			)
			(layer "F.SilkS")
		)
		(fp_line
			(start -0.7874 -0.4064)
			(end 0.7874 -0.4064)
			(stroke
				(width 0.1524)
				(type default)
			)
			(layer "F.SilkS")
		)
		(fp_line
			(start 0.67945 0.3048)
			(end 0.120396 0.3048)
			(stroke
				(width 0.1)
				(type default)
			)
			(layer "F.Fab")
		)
		(fp_line
			(start 0.67945 -0.3048)
			(end 0.67945 0.3048)
			(stroke
				(width 0.1)
				(type default)
			)
			(layer "F.Fab")
		)
		(fp_line
			(start 0.12065 -0.2794)
			(end 0.12065 -0.3048)
			(stroke
				(width 0.1)
				(type default)
			)
			(layer "F.Fab")
		)
		(fp_line
			(start 0.12065 -0.3048)
			(end 0.67945 -0.3048)
			(stroke
				(width 0.1)
				(type default)
			)
			(layer "F.Fab")
		)
		(fp_line
			(start 0.120396 0.3048)
			(end 0.120396 0.2794)
			(stroke
				(width 0.1)
				(type default)
			)
			(layer "F.Fab")
		)
		(fp_line
			(start 0.120396 0.2794)
			(end -0.12065 0.2794)
			(stroke
				(width 0.1)
				(type default)
			)
			(layer "F.Fab")
		)
		(fp_line
			(start -0.12065 0.3048)
			(end -0.67945 0.3048)
			(stroke
				(width 0.1)
				(type default)
			)
			(layer "F.Fab")
		)
		(fp_line
			(start -0.12065 0.2794)
			(end -0.12065 0.3048)
			(stroke
				(width 0.1)
				(type default)
			)
			(layer "F.Fab")
		)
		(fp_line
			(start -0.12065 -0.2794)
			(end 0.12065 -0.2794)
			(stroke
				(width 0.1)
				(type default)
			)
			(layer "F.Fab")
		)
		(fp_line
			(start -0.12065 -0.305054)
			(end -0.12065 -0.2794)
			(stroke
				(width 0.1)
				(type default)
			)
			(layer "F.Fab")
		)
		(fp_line
			(start -0.67945 0.3048)
			(end -0.67945 -0.305054)
			(stroke
				(width 0.1)
				(type default)
			)
			(layer "F.Fab")
		)
		(fp_line
			(start -0.67945 -0.305054)
			(end -0.12065 -0.305054)
			(stroke
				(width 0.1)
				(type default)
			)
			(layer "F.Fab")
		)
		(pad "1" smd circle
			(at -0.40005 0 180)
			(size 0 0)
			(layers "F.Cu" "F.Mask" "F.Paste")
			(net "P12V_NIC0_R")
		)
		(pad "2" smd circle
			(at 0.40005 0 180)
			(size 0 0)
			(layers "F.Cu" "F.Mask" "F.Paste")
			(net "P12V_NIC0_CO_AVIN_PD")
		)
	)
	(footprint ""
		(layer "F.Cu")
		(at 196.639434 -159.235648 180)
		(property "Reference" "R195"
			(at 0 0 180)
			(layer "F.SilkS")
			(hide yes)
			(effects
				(font
					(size 1.27 1.27)
				)
			)
		)
		(property "Value" ""
			(at 0 0 180)
			(layer "F.Fab")
			(effects
				(font
					(size 1.27 1.27)
				)
			)
		)
		(duplicate_pad_numbers_are_jumpers no)
		(fp_line
			(start 0.7874 0.4064)
			(end -0.7874 0.4064)
			(stroke
				(width 0.1524)
				(type default)
			)
			(layer "F.SilkS")
		)
		(fp_line
			(start 0.7874 -0.4064)
			(end 0.7874 0.4064)
			(stroke
				(width 0.1524)
				(type default)
			)
			(layer "F.SilkS")
		)
		(fp_line
			(start -0.7874 0.4064)
			(end -0.7874 -0.4064)
			(stroke
				(width 0.1524)
				(type default)
			)
			(layer "F.SilkS")
		)
		(fp_line
			(start -0.7874 -0.4064)
			(end 0.7874 -0.4064)
			(stroke
				(width 0.1524)
				(type default)
			)
			(layer "F.SilkS")
		)
		(fp_line
			(start 0.67945 0.3048)
			(end 0.120396 0.3048)
			(stroke
				(width 0.1)
				(type default)
			)
			(layer "F.Fab")
		)
		(fp_line
			(start 0.67945 -0.3048)
			(end 0.67945 0.3048)
			(stroke
				(width 0.1)
				(type default)
			)
			(layer "F.Fab")
		)
		(fp_line
			(start 0.12065 -0.2794)
			(end 0.12065 -0.3048)
			(stroke
				(width 0.1)
				(type default)
			)
			(layer "F.Fab")
		)
		(fp_line
			(start 0.12065 -0.3048)
			(end 0.67945 -0.3048)
			(stroke
				(width 0.1)
				(type default)
			)
			(layer "F.Fab")
		)
		(fp_line
			(start 0.120396 0.3048)
			(end 0.120396 0.2794)
			(stroke
				(width 0.1)
				(type default)
			)
			(layer "F.Fab")
		)
		(fp_line
			(start 0.120396 0.2794)
			(end -0.12065 0.2794)
			(stroke
				(width 0.1)
				(type default)
			)
			(layer "F.Fab")
		)
		(fp_line
			(start -0.12065 0.3048)
			(end -0.67945 0.3048)
			(stroke
				(width 0.1)
				(type default)
			)
			(layer "F.Fab")
		)
		(fp_line
			(start -0.12065 0.2794)
			(end -0.12065 0.3048)
			(stroke
				(width 0.1)
				(type default)
			)
			(layer "F.Fab")
		)
		(fp_line
			(start -0.12065 -0.2794)
			(end 0.12065 -0.2794)
			(stroke
				(width 0.1)
				(type default)
			)
			(layer "F.Fab")
		)
		(fp_line
			(start -0.12065 -0.305054)
			(end -0.12065 -0.2794)
			(stroke
				(width 0.1)
				(type default)
			)
			(layer "F.Fab")
		)
		(fp_line
			(start -0.67945 0.3048)
			(end -0.67945 -0.305054)
			(stroke
				(width 0.1)
				(type default)
			)
			(layer "F.Fab")
		)
		(fp_line
			(start -0.67945 -0.305054)
			(end -0.12065 -0.305054)
			(stroke
				(width 0.1)
				(type default)
			)
			(layer "F.Fab")
		)
		(pad "1" smd circle
			(at -0.40005 0 180)
			(size 0 0)
			(layers "F.Cu" "F.Mask" "F.Paste")
			(net "PRSNT_NIC3_N")
		)
		(pad "2" smd circle
			(at 0.40005 0 180)
			(size 0 0)
			(layers "F.Cu" "F.Mask" "F.Paste")
			(net "PRSNTB3_NIC3_N")
		)
	)
	(footprint ""
		(layer "F.Cu")
		(at 277.44674 -38.49116 180)
		(property "Reference" "R6100"
			(at 0 0 180)
			(layer "F.SilkS")
			(hide yes)
			(effects
				(font
					(size 1.27 1.27)
				)
			)
		)
		(property "Value" ""
			(at 0 0 180)
			(layer "F.Fab")
			(effects
				(font
					(size 1.27 1.27)
				)
			)
		)
		(duplicate_pad_numbers_are_jumpers no)
		(fp_line
			(start 0.7874 0.4064)
			(end -0.7874 0.4064)
			(stroke
				(width 0.1524)
				(type default)
			)
			(layer "F.SilkS")
		)
		(fp_line
			(start 0.7874 -0.4064)
			(end 0.7874 0.4064)
			(stroke
				(width 0.1524)
				(type default)
			)
			(layer "F.SilkS")
		)
		(fp_line
			(start -0.7874 0.4064)
			(end -0.7874 -0.4064)
			(stroke
				(width 0.1524)
				(type default)
			)
			(layer "F.SilkS")
		)
		(fp_line
			(start -0.7874 -0.4064)
			(end 0.7874 -0.4064)
			(stroke
				(width 0.1524)
				(type default)
			)
			(layer "F.SilkS")
		)
		(fp_line
			(start 0.67945 0.3048)
			(end 0.120396 0.3048)
			(stroke
				(width 0.1)
				(type default)
			)
			(layer "F.Fab")
		)
		(fp_line
			(start 0.67945 -0.3048)
			(end 0.67945 0.3048)
			(stroke
				(width 0.1)
				(type default)
			)
			(layer "F.Fab")
		)
		(fp_line
			(start 0.12065 -0.2794)
			(end 0.12065 -0.3048)
			(stroke
				(width 0.1)
				(type default)
			)
			(layer "F.Fab")
		)
		(fp_line
			(start 0.12065 -0.3048)
			(end 0.67945 -0.3048)
			(stroke
				(width 0.1)
				(type default)
			)
			(layer "F.Fab")
		)
		(fp_line
			(start 0.120396 0.3048)
			(end 0.120396 0.2794)
			(stroke
				(width 0.1)
				(type default)
			)
			(layer "F.Fab")
		)
		(fp_line
			(start 0.120396 0.2794)
			(end -0.12065 0.2794)
			(stroke
				(width 0.1)
				(type default)
			)
			(layer "F.Fab")
		)
		(fp_line
			(start -0.12065 0.3048)
			(end -0.67945 0.3048)
			(stroke
				(width 0.1)
				(type default)
			)
			(layer "F.Fab")
		)
		(fp_line
			(start -0.12065 0.2794)
			(end -0.12065 0.3048)
			(stroke
				(width 0.1)
				(type default)
			)
			(layer "F.Fab")
		)
		(fp_line
			(start -0.12065 -0.2794)
			(end 0.12065 -0.2794)
			(stroke
				(width 0.1)
				(type default)
			)
			(layer "F.Fab")
		)
		(fp_line
			(start -0.12065 -0.305054)
			(end -0.12065 -0.2794)
			(stroke
				(width 0.1)
				(type default)
			)
			(layer "F.Fab")
		)
		(fp_line
			(start -0.67945 0.3048)
			(end -0.67945 -0.305054)
			(stroke
				(width 0.1)
				(type default)
			)
			(layer "F.Fab")
		)
		(fp_line
			(start -0.67945 -0.305054)
			(end -0.12065 -0.305054)
			(stroke
				(width 0.1)
				(type default)
			)
			(layer "F.Fab")
		)
		(pad "1" smd circle
			(at -0.40005 0 180)
			(size 0 0)
			(layers "F.Cu" "F.Mask" "F.Paste")
			(net "P3V3_SSD10_PG_G1")
		)
		(pad "2" smd circle
			(at 0.40005 0 180)
			(size 0 0)
			(layers "F.Cu" "F.Mask" "F.Paste")
			(net "GND")
		)
	)
)
